(kicad_pcb
	(version 20241229)
	(generator "pcbnew")
	(generator_version "9.0")
	(general
		(thickness 1.294)
		(legacy_teardrops no)
	)
	(paper "A3")
	(title_block
		(title "Kintex 410T devboard")
		(date "2024-04-03")
		(rev "1.1.2")
		(comment 9 "footprints 373-376 of 975")
	)
	(layers
		(0 "F.Cu" mixed)
		(4 "In1.Cu" power)
		(6 "In2.Cu" power)
		(8 "In3.Cu" mixed)
		(10 "In4.Cu" power)
		(12 "In5.Cu" mixed)
		(14 "In6.Cu" power)
		(16 "In7.Cu" mixed)
		(18 "In8.Cu" power)
		(2 "B.Cu" mixed)
		(9 "F.Adhes" user "F.Adhesive")
		(11 "B.Adhes" user "B.Adhesive")
		(13 "F.Paste" user)
		(15 "B.Paste" user)
		(5 "F.SilkS" user "F.Silkscreen")
		(7 "B.SilkS" user "B.Silkscreen")
		(1 "F.Mask" user)
		(3 "B.Mask" user)
		(17 "Dwgs.User" user "User.Drawings")
		(19 "Cmts.User" user "User.Comments")
		(21 "Eco1.User" user "User.Eco1")
		(23 "Eco2.User" user "User.Eco2")
		(25 "Edge.Cuts" user)
		(27 "Margin" user)
		(31 "F.CrtYd" user "F.Courtyard")
		(29 "B.CrtYd" user "B.Courtyard")
		(35 "F.Fab" user)
		(33 "B.Fab" user)
	)
	(footprint "antmicro-footprints:DHVQFN-14-1EP_2.5x3mm"
		(layer "F.Cu")
		(at 239.6 137.7 180)
		(property "Reference" "U24"
			(at -2.625 -1.85 270)
			(layer "F.SilkS")
			(effects
				(font
					(size 0.7 0.7)
					(thickness 0.15)
				)
				(justify left bottom)
			)
		)
		(property "Value" "TXU0304BQAR"
			(at 0 2.898 180)
			(layer "F.Fab")
			(effects
				(font
					(size 0.7 0.7)
					(thickness 0.15)
				)
				(justify left bottom)
			)
		)
		(property "Description" "Logic translator/level shifter"
			(at 0 0 180)
			(layer "F.Fab")
			(hide yes)
			(effects
				(font
					(size 1.27 1.27)
					(thickness 0.15)
				)
			)
		)
		(property "Author" "Antmicro"
			(at 479.2 275.4 0)
			(layer "F.Fab")
			(hide yes)
			(effects
				(font
					(size 1 1)
					(thickness 0.15)
				)
			)
		)
		(property "License" "Apache-2.0"
			(at 479.2 275.4 0)
			(layer "F.Fab")
			(hide yes)
			(effects
				(font
					(size 1 1)
					(thickness 0.15)
				)
			)
		)
		(property "MPN" "TXU0304BQAR"
			(at 479.2 275.4 0)
			(layer "F.Fab")
			(hide yes)
			(effects
				(font
					(size 1 1)
					(thickness 0.15)
				)
			)
		)
		(property "Manufacturer" "Texas Instruments"
			(at 479.2 275.4 0)
			(layer "F.Fab")
			(hide yes)
			(effects
				(font
					(size 1 1)
					(thickness 0.15)
				)
			)
		)
		(sheetname "USB PHY")
		(sheetfile "usb-phy.kicad_sch")
		(attr smd)
		(fp_line
			(start 1.35 1.6)
			(end 1.35 1.249)
			(stroke
				(width 0.15)
				(type solid)
			)
			(layer "F.SilkS")
		)
		(fp_line
			(start 1.35 -1.601)
			(end 1.35 -1.25)
			(stroke
				(width 0.15)
				(type solid)
			)
			(layer "F.SilkS")
		)
		(fp_line
			(start 1.35 -1.601)
			(end 0.494 -1.601)
			(stroke
				(width 0.15)
				(type solid)
			)
			(layer "F.SilkS")
		)
		(fp_line
			(start 0.494 1.6)
			(end 1.35 1.6)
			(stroke
				(width 0.15)
				(type solid)
			)
			(layer "F.SilkS")
		)
		(fp_line
			(start -1.35 -1.601)
			(end -1.35 -1.25)
			(stroke
				(width 0.15)
				(type solid)
			)
			(layer "F.SilkS")
		)
		(fp_line
			(start -1.351 1.6)
			(end -0.5 1.6)
			(stroke
				(width 0.15)
				(type solid)
			)
			(layer "F.SilkS")
		)
		(fp_line
			(start -1.351 1.6)
			(end -1.351 1.249)
			(stroke
				(width 0.15)
				(type solid)
			)
			(layer "F.SilkS")
		)
		(fp_line
			(start -1.351 -1.601)
			(end -0.5 -1.601)
			(stroke
				(width 0.15)
				(type solid)
			)
			(layer "F.SilkS")
		)
		(fp_circle
			(center -0.7 -1.85)
			(end -0.653 -1.85)
			(stroke
				(width 0.15)
				(type solid)
			)
			(fill yes)
			(layer "F.SilkS")
		)
		(fp_rect
			(start -1.85 -2)
			(end 1.8 1.95)
			(stroke
				(width 0.05)
				(type solid)
			)
			(fill no)
			(layer "F.CrtYd")
		)
		(fp_line
			(start 1.249 1.499)
			(end -1.25 1.499)
			(stroke
				(width 0.15)
				(type solid)
			)
			(layer "F.Fab")
		)
		(fp_line
			(start 1.249 -1.5)
			(end 1.249 1.499)
			(stroke
				(width 0.15)
				(type solid)
			)
			(layer "F.Fab")
		)
		(fp_line
			(start -1 -1.5)
			(end 1.249 -1.5)
			(stroke
				(width 0.15)
				(type solid)
			)
			(layer "F.Fab")
		)
		(fp_line
			(start -1.25 1.499)
			(end -1.25 -1.25)
			(stroke
				(width 0.15)
				(type solid)
			)
			(layer "F.Fab")
		)
		(fp_line
			(start -1.25 -1.25)
			(end -1 -1.5)
			(stroke
				(width 0.15)
				(type solid)
			)
			(layer "F.Fab")
		)
		(pad "1" smd oval
			(at -0.25 -1.5 180)
			(size 0.3 0.8)
			(layers "F.Cu" "F.Mask" "F.Paste")
			(net 707 "/USB PHY/FTDI_3V3")
			(pinfunction "VCCA")
			(pintype "power_in")
		)
		(pad "2" smd oval
			(at -1.25 -1 270)
			(size 0.3 0.8)
			(layers "F.Cu" "F.Mask" "F.Paste")
			(net 1023 "/USB PHY/BDBUS0")
			(pinfunction "A1")
			(pintype "input")
		)
		(pad "3" smd oval
			(at -1.25 -0.5 270)
			(size 0.3 0.8)
			(layers "F.Cu" "F.Mask" "F.Paste")
			(net 1 "GND")
			(pinfunction "A2")
			(pintype "input")
		)
		(pad "4" smd oval
			(at -1.25 0 270)
			(size 0.3 0.8)
			(layers "F.Cu" "F.Mask" "F.Paste")
			(net 1024 "/USB PHY/BDBUS1")
			(pinfunction "A3")
			(pintype "input")
		)
		(pad "5" smd oval
			(at -1.25 0.494 270)
			(size 0.3 0.8)
			(layers "F.Cu" "F.Mask" "F.Paste")
			(net 1025 "/USB PHY/BDBUS2")
			(pinfunction "A4Y")
			(pintype "output")
		)
		(pad "6" smd oval
			(at -1.25 0.994 270)
			(size 0.3 0.8)
			(layers "F.Cu" "F.Mask" "F.Paste")
			(net 1306 "unconnected-(U24-NC-Pad6)")
			(pinfunction "NC")
			(pintype "no_connect")
		)
		(pad "7" smd oval
			(at -0.25 1.499 180)
			(size 0.3 0.8)
			(layers "F.Cu" "F.Mask" "F.Paste")
			(net 1 "GND")
			(pinfunction "GND")
			(pintype "passive")
		)
		(pad "8" smd oval
			(at 0.244 1.499 180)
			(size 0.3 0.8)
			(layers "F.Cu" "F.Mask" "F.Paste")
			(net 379 "Net-(U24-OE)")
			(pinfunction "OE")
			(pintype "tri_state")
		)
		(pad "9" smd oval
			(at 1.249 0.994 270)
			(size 0.3 0.8)
			(layers "F.Cu" "F.Mask" "F.Paste")
			(net 1357 "unconnected-(U24-NC-Pad9)")
			(pinfunction "NC")
			(pintype "no_connect")
		)
		(pad "10" smd oval
			(at 1.249 0.494 270)
			(size 0.3 0.8)
			(layers "F.Cu" "F.Mask" "F.Paste")
			(net 942 "/USB PHY/FTDI_SDA_IN")
			(pinfunction "B4")
			(pintype "input")
		)
		(pad "11" smd oval
			(at 1.249 0 270)
			(size 0.3 0.8)
			(layers "F.Cu" "F.Mask" "F.Paste")
			(net 1047 "/USB PHY/FTDI_SDA_OUT")
			(pinfunction "B3Y")
			(pintype "output")
		)
		(pad "12" smd oval
			(at 1.249 -0.5 270)
			(size 0.3 0.8)
			(layers "F.Cu" "F.Mask" "F.Paste")
			(net 1368 "unconnected-(U24-B2Y-Pad12)")
			(pinfunction "B2Y")
			(pintype "output+no_connect")
		)
		(pad "13" smd oval
			(at 1.249 -1 270)
			(size 0.3 0.8)
			(layers "F.Cu" "F.Mask" "F.Paste")
			(net 941 "/USB PHY/FTDI_SCL")
			(pinfunction "B1Y")
			(pintype "output")
		)
		(pad "14" smd oval
			(at 0.244 -1.5 180)
			(size 0.3 0.8)
			(layers "F.Cu" "F.Mask" "F.Paste")
			(net 24 "+3V3")
			(pinfunction "VCCB")
			(pintype "power_in")
		)
		(pad "15" smd rect
			(at 0 0 180)
			(size 1 1.5)
			(layers "F.Cu" "F.Mask" "F.Paste")
			(net 1 "GND")
			(pinfunction "GND")
			(pintype "power_in")
		)
	)
	(footprint "antmicro-footprints:C_0603_1608Metric"
		(layer "F.Cu")
		(at 170.85 172.8125 -90)
		(descr "Capacitor SMD 0603")
		(tags "capacitor 0603")
		(property "Reference" "C333"
			(at -6.5625 3.2 90)
			(layer "F.SilkS")
			(effects
				(font
					(size 0.7 0.7)
					(thickness 0.15)
				)
				(justify right bottom)
			)
		)
		(property "Value" "C_22u_0603"
			(at 0 1.6 90)
			(layer "F.Fab")
			(effects
				(font
					(size 0.7 0.7)
					(thickness 0.15)
				)
				(justify right bottom)
			)
		)
		(property "Description" "SMD Multilayer Ceramic Capacitor, 22 µF, 6.3 V, 0603 [1608 Metric], ± 20%, X5R, GRM Series"
			(at 0 0 270)
			(layer "F.Fab")
			(hide yes)
			(effects
				(font
					(size 1.27 1.27)
					(thickness 0.15)
				)
			)
		)
		(property "Author" "Antmicro"
			(at -1.9625 343.6625 0)
			(layer "F.Fab")
			(hide yes)
			(effects
				(font
					(size 1 1)
					(thickness 0.15)
				)
			)
		)
		(property "Dielectric" ""
			(at -1.9625 343.6625 0)
			(layer "F.Fab")
			(hide yes)
			(effects
				(font
					(size 1 1)
					(thickness 0.15)
				)
			)
		)
		(property "License" "Apache-2.0"
			(at -1.9625 343.6625 0)
			(layer "F.Fab")
			(hide yes)
			(effects
				(font
					(size 1 1)
					(thickness 0.15)
				)
			)
		)
		(property "MPN" "GRM188R60J226MEA0D"
			(at -1.9625 343.6625 0)
			(layer "F.Fab")
			(hide yes)
			(effects
				(font
					(size 1 1)
					(thickness 0.15)
				)
			)
		)
		(property "Manufacturer" "Murata"
			(at -1.9625 343.6625 0)
			(layer "F.Fab")
			(hide yes)
			(effects
				(font
					(size 1 1)
					(thickness 0.15)
				)
			)
		)
		(property "Val" "22u"
			(at -1.9625 343.6625 0)
			(layer "F.Fab")
			(hide yes)
			(effects
				(font
					(size 1 1)
					(thickness 0.15)
				)
			)
		)
		(property "Voltage" ""
			(at -1.9625 343.6625 0)
			(layer "F.Fab")
			(hide yes)
			(effects
				(font
					(size 1 1)
					(thickness 0.15)
				)
			)
		)
		(sheetname "DC-DC Converters")
		(sheetfile "dc-dc.kicad_sch")
		(attr smd)
		(fp_line
			(start -0.15 0.4)
			(end 0.15 0.4)
			(stroke
				(width 0.15)
				(type solid)
			)
			(layer "F.SilkS")
		)
		(fp_line
			(start -0.15 -0.4)
			(end 0.15 -0.4)
			(stroke
				(width 0.15)
				(type solid)
			)
			(layer "F.SilkS")
		)
		(fp_rect
			(start -1.25 -0.65)
			(end 1.25 0.65)
			(stroke
				(width 0.05)
				(type solid)
			)
			(fill no)
			(layer "F.CrtYd")
		)
		(fp_rect
			(start -0.8 -0.4)
			(end 0.8 0.4)
			(stroke
				(width 0.15)
				(type solid)
			)
			(fill no)
			(layer "F.Fab")
		)
		(pad "1" smd roundrect
			(at -0.7 0 270)
			(size 0.8 1)
			(layers "F.Cu" "F.Mask" "F.Paste")
			(roundrect_rratio 0.2)
			(net 1 "GND")
			(pintype "passive")
		)
		(pad "2" smd roundrect
			(at 0.7 0 270)
			(size 0.8 1)
			(layers "F.Cu" "F.Mask" "F.Paste")
			(roundrect_rratio 0.2)
			(net 740 "/DC-DC Converters/1V35_local")
			(pintype "passive")
		)
	)
	(footprint "antmicro-footprints:C_0402_1005Metric"
		(layer "F.Cu")
		(at 207.403752 95.634 180)
		(descr "Capacitor SMD 0402")
		(tags "capacitor SMD 0402")
		(property "Reference" "C289"
			(at 1.753752 7.134 180)
			(layer "F.SilkS")
			(effects
				(font
					(size 0.7 0.7)
					(thickness 0.15)
				)
				(justify left bottom)
			)
		)
		(property "Value" "C_100n_0402"
			(at 0 1.169 180)
			(layer "F.Fab")
			(effects
				(font
					(size 0.7 0.7)
					(thickness 0.15)
				)
				(justify left bottom)
			)
		)
		(property "Description" "SMD Multilayer Ceramic Capacitor, 0.1 µF, 50 V, 0402 [1005 Metric], ± 10%, X5R, GRM Series"
			(at 0 0 180)
			(layer "F.Fab")
			(hide yes)
			(effects
				(font
					(size 1.27 1.27)
					(thickness 0.15)
				)
			)
		)
		(property "Author" "Antmicro"
			(at 414.807504 191.268 0)
			(layer "F.Fab")
			(hide yes)
			(effects
				(font
					(size 1 1)
					(thickness 0.15)
				)
			)
		)
		(property "Dielectric" "X5R"
			(at 414.807504 191.268 0)
			(layer "F.Fab")
			(hide yes)
			(effects
				(font
					(size 1 1)
					(thickness 0.15)
				)
			)
		)
		(property "License" "Apache-2.0"
			(at 414.807504 191.268 0)
			(layer "F.Fab")
			(hide yes)
			(effects
				(font
					(size 1 1)
					(thickness 0.15)
				)
			)
		)
		(property "MPN" "GRM155R61H104KE14D"
			(at 414.807504 191.268 0)
			(layer "F.Fab")
			(hide yes)
			(effects
				(font
					(size 1 1)
					(thickness 0.15)
				)
			)
		)
		(property "Manufacturer" "Murata"
			(at 414.807504 191.268 0)
			(layer "F.Fab")
			(hide yes)
			(effects
				(font
					(size 1 1)
					(thickness 0.15)
				)
			)
		)
		(property "Val" "100n"
			(at 414.807504 191.268 0)
			(layer "F.Fab")
			(hide yes)
			(effects
				(font
					(size 1 1)
					(thickness 0.15)
				)
			)
		)
		(property "Voltage" "50V"
			(at 414.807504 191.268 0)
			(layer "F.Fab")
			(hide yes)
			(effects
				(font
					(size 1 1)
					(thickness 0.15)
				)
			)
		)
		(sheetname "HDMI + Ethernet")
		(sheetfile "hdmi-ethernet.kicad_sch")
		(attr smd)
		(fp_rect
			(start -0.925 -0.47)
			(end 0.925 0.47)
			(stroke
				(width 0.05)
				(type default)
			)
			(fill no)
			(layer "F.CrtYd")
		)
		(fp_line
			(start 0.504 0.248)
			(end -0.494 0.248)
			(stroke
				(width 0.15)
				(type solid)
			)
			(layer "F.Fab")
		)
		(fp_line
			(start 0.504 -0.25)
			(end 0.504 0.248)
			(stroke
				(width 0.15)
				(type solid)
			)
			(layer "F.Fab")
		)
		(fp_line
			(start -0.494 0.248)
			(end -0.494 -0.25)
			(stroke
				(width 0.15)
				(type solid)
			)
			(layer "F.Fab")
		)
		(fp_line
			(start -0.494 -0.25)
			(end 0.504 -0.25)
			(stroke
				(width 0.15)
				(type solid)
			)
			(layer "F.Fab")
		)
		(pad "1" smd roundrect
			(at -0.48 0 180)
			(size 0.59 0.64)
			(layers "F.Cu" "F.Mask" "F.Paste")
			(roundrect_rratio 0.25)
			(net 1 "GND")
			(pintype "passive")
		)
		(pad "2" smd roundrect
			(at 0.48 0 180)
			(size 0.59 0.64)
			(layers "F.Cu" "F.Mask" "F.Paste")
			(roundrect_rratio 0.25)
			(net 728 "/HDMI + Ethernet/GBE_AVDDL{slash}PLL")
			(pintype "passive")
		)
	)
	(footprint "antmicro-footprints:R_0603_1608Metric"
		(layer "F.Cu")
		(at 166.3 172.8 90)
		(descr "Resistor SMD 0603")
		(tags "resistor SMD 0603")
		(property "Reference" "R287"
			(at -1.49 1.41 90)
			(layer "F.SilkS")
			(effects
				(font
					(size 0.7 0.7)
					(thickness 0.15)
				)
				(justify left bottom)
			)
		)
		(property "Value" "R_0R_22.4A_0603"
			(at 0 1.6 90)
			(layer "F.Fab")
			(effects
				(font
					(size 0.7 0.7)
					(thickness 0.15)
				)
				(justify left bottom)
			)
		)
		(property "Description" "SMD Chip Resistor"
			(at 0 0 90)
			(layer "F.Fab")
			(hide yes)
			(effects
				(font
					(size 1.27 1.27)
					(thickness 0.15)
				)
			)
		)
		(property "Author" "Antmicro"
			(at 339.1 6.5 0)
			(layer "F.Fab")
			(hide yes)
			(effects
				(font
					(size 1 1)
					(thickness 0.15)
				)
			)
		)
		(property "License" "Apache-2.0"
			(at 339.1 6.5 0)
			(layer "F.Fab")
			(hide yes)
			(effects
				(font
					(size 1 1)
					(thickness 0.15)
				)
			)
		)
		(property "MPN" "PMR03EZPJ000"
			(at 339.1 6.5 0)
			(layer "F.Fab")
			(hide yes)
			(effects
				(font
					(size 1 1)
					(thickness 0.15)
				)
			)
		)
		(property "Manufacturer" "ROHM Semiconductor"
			(at 339.1 6.5 0)
			(layer "F.Fab")
			(hide yes)
			(effects
				(font
					(size 1 1)
					(thickness 0.15)
				)
			)
		)
		(property "Max. Curr." "22.4A"
			(at 339.1 6.5 0)
			(layer "F.Fab")
			(hide yes)
			(effects
				(font
					(size 1 1)
					(thickness 0.15)
				)
			)
		)
		(property "Tolerance" "template_tolerance"
			(at 339.1 6.5 0)
			(layer "F.Fab")
			(hide yes)
			(effects
				(font
					(size 1 1)
					(thickness 0.15)
				)
			)
		)
		(property "Val" "0R"
			(at 339.1 6.5 0)
			(layer "F.Fab")
			(hide yes)
			(effects
				(font
					(size 1 1)
					(thickness 0.15)
				)
			)
		)
		(sheetname "DC-DC Converters")
		(sheetfile "dc-dc.kicad_sch")
		(attr smd)
		(fp_line
			(start -0.15 -0.4)
			(end 0.15 -0.4)
			(stroke
				(width 0.15)
				(type solid)
			)
			(layer "F.SilkS")
		)
		(fp_line
			(start -0.15 0.4)
			(end 0.15 0.4)
			(stroke
				(width 0.15)
				(type solid)
			)
			(layer "F.SilkS")
		)
		(fp_rect
			(start -1.25 -0.65)
			(end 1.25 0.65)
			(stroke
				(width 0.05)
				(type solid)
			)
			(fill no)
			(layer "F.CrtYd")
		)
		(fp_rect
			(start -0.8 -0.4)
			(end 0.8 0.4)
			(stroke
				(width 0.15)
				(type solid)
			)
			(fill no)
			(layer "F.Fab")
		)
		(pad "1" smd roundrect
			(at -0.7 0 90)
			(size 0.8 1)
			(layers "F.Cu" "F.Mask" "F.Paste")
			(roundrect_rratio 0.2)
			(net 737 "/DC-DC Converters/1V2_local")
			(pintype "passive")
		)
		(pad "2" smd roundrect
			(at 0.7 0 90)
			(size 0.8 1)
			(layers "F.Cu" "F.Mask" "F.Paste")
			(roundrect_rratio 0.2)
			(net 727 "+1V2")
			(pintype "passive")
		)
	)
)
